# BASEBOARD_FAB2 (Tioga Pass) — schematic netlist excerpt (pin names and nets, part order shuffled) for the footprints in the layout excerpt that follows; sources: Cadence DE-HDL packaged netlist, KiCad conversion of Wiwynn_Tioga_Pass_MB.brd

Y6F1  OSC_C  156.25MHZ OSC  pkg 6P10  page 104
  ENABLE_DISABLE  = FM_CPU0_STL_BRD_OSC_EN
  NC_GND  = NC_CLK_156M_CPU0_OSC
  GND  = GND
  \out\  = CLK_156M_OSC_BRD_CPU0_DP
  OUT_N  = CLK_156M_OSC_BRD_CPU0_DN
  VCC  = P3V3

T1P3  TPAD-DIFF-4P-GP  pkg DISCRET-GB3  page 256
  \1\  = L5_85OHM_6INCH_DP
  \2\  = L5_85OHM_6INCH_DN
  GND1  = GND
  GND2  = GND

(kicad_pcb
	(version 20260206)
	(generator "pcbnew")
	(generator_version "10.0")
	(general
		(thickness 1.6)
		(legacy_teardrops no)
	)
	(paper "A4")
	(title_block
		(title "Wiwynn_Tioga_Pass_MB.brd")
		(comment 1 "Tioga Pass / footprints 2064-2065 of 4770")
	)
	(layers
		(0 "F.Cu" signal "TOP")
		(4 "In1.Cu" signal "L2GND")
		(6 "In2.Cu" signal "L3")
		(8 "In3.Cu" signal "L4GND")
		(10 "In4.Cu" signal "L5")
		(12 "In5.Cu" signal "L6GND")
		(14 "In6.Cu" signal "L7VCC")
		(16 "In7.Cu" signal "L8VCC")
		(18 "In8.Cu" signal "L9GND")
		(20 "In9.Cu" signal "L10")
		(22 "In10.Cu" signal "L11GND")
		(24 "In11.Cu" signal "L12")
		(26 "In12.Cu" signal "L13GND")
		(2 "B.Cu" signal "BOTTOM")
		(9 "F.Adhes" user "F.Adhesive")
		(11 "B.Adhes" user "B.Adhesive")
		(13 "F.Paste" user "Package Geometry/Pastemask Top")
		(15 "B.Paste" user "Package Geometry/Pastemask Bottom")
		(5 "F.SilkS" user "Ref Des/Silkscreen Top")
		(7 "B.SilkS" user "Ref Des/Silkscreen Bottom")
		(1 "F.Mask" user "Board Geometry/Soldermask Top")
		(3 "B.Mask" user "Board Geometry/Soldermask Bottom")
		(17 "Dwgs.User" user "User.Drawings")
		(19 "Cmts.User" user "User.Comments")
		(21 "Eco1.User" user "User.Eco1")
		(23 "Eco2.User" user "User.Eco2")
		(25 "Edge.Cuts" user "Board Geometry/Outline")
		(27 "Margin" user)
		(31 "F.CrtYd" user "Package Geometry/Place Bound Top")
		(29 "B.CrtYd" user "Package Geometry/Place Bound Bottom")
		(35 "F.Fab" user "Ref Des/Assembly Top")
		(33 "B.Fab" user "Ref Des/Assembly Bottom")
	)
	(footprint ""
		(layer "F.Cu")
		(at 312.650124 -30.26537)
		(property "Reference" "Y6F1"
			(at -0.1397 -2.153412 0)
			(unlocked yes)
			(layer "F.SilkS")
			(effects
				(font
					(size 0.7874 0.5842)
					(thickness 0.1524)
				)
				(justify left)
			)
		)
		(property "Value" ""
			(at 0 0 0)
			(layer "F.Fab")
			(effects
				(font
					(size 1.27 1.27)
				)
			)
		)
		(duplicate_pad_numbers_are_jumpers no)
		(fp_line
			(start -0.366522 -1.329944)
			(end 3.033522 -1.329944)
			(stroke
				(width 0.1524)
				(type default)
			)
			(layer "F.SilkS")
		)
		(fp_line
			(start -0.366522 -0.80391)
			(end -0.366522 -1.329944)
			(stroke
				(width 0.1524)
				(type default)
			)
			(layer "F.SilkS")
		)
		(fp_line
			(start -0.366522 3.869944)
			(end -0.366522 3.363468)
			(stroke
				(width 0.1524)
				(type default)
			)
			(layer "F.SilkS")
		)
		(fp_line
			(start 3.033522 -1.329944)
			(end 3.033522 -0.790956)
			(stroke
				(width 0.1524)
				(type default)
			)
			(layer "F.SilkS")
		)
		(fp_line
			(start 3.033522 3.370072)
			(end 3.033522 3.869944)
			(stroke
				(width 0.1524)
				(type default)
			)
			(layer "F.SilkS")
		)
		(fp_line
			(start 3.033522 3.869944)
			(end -0.366522 3.869944)
			(stroke
				(width 0.1524)
				(type default)
			)
			(layer "F.SilkS")
		)
		(fp_circle
			(center -1.406398 -0.537718)
			(end -1.279398 -0.537718)
			(stroke
				(width 0.254)
				(type default)
			)
			(fill no)
			(layer "F.SilkS")
		)
		(fp_rect
			(start -0.366522 3.869944)
			(end 3.033522 -1.329944)
			(stroke
				(width 0)
				(type default)
			)
			(fill no)
			(layer "F.CrtYd")
		)
		(fp_line
			(start -0.366522 -1.329944)
			(end 3.033522 -1.329944)
			(stroke
				(width 0.1)
				(type default)
			)
			(layer "F.Fab")
		)
		(fp_line
			(start -0.366522 3.869944)
			(end -0.366522 -1.329944)
			(stroke
				(width 0.1)
				(type default)
			)
			(layer "F.Fab")
		)
		(fp_line
			(start 3.033522 -1.329944)
			(end 3.033522 3.869944)
			(stroke
				(width 0.1)
				(type default)
			)
			(layer "F.Fab")
		)
		(fp_line
			(start 3.033522 3.869944)
			(end -0.366522 3.869944)
			(stroke
				(width 0.1)
				(type default)
			)
			(layer "F.Fab")
		)
		(fp_circle
			(center -1.405128 -0.544068)
			(end -1.278128 -0.544068)
			(stroke
				(width 0.254)
				(type default)
			)
			(fill no)
			(layer "F.Fab")
		)
		(pad "1" smd rect
			(at 0 0)
			(size 1.651 0.8382)
			(layers "F.Cu" "F.Mask" "F.Paste")
			(net "FM_CPU0_STL_BRD_OSC_EN")
		)
		(pad "2" smd rect
			(at 0 1.27)
			(size 1.651 0.8382)
			(layers "F.Cu" "F.Mask" "F.Paste")
			(net "NC_CLK_156M_CPU0_OSC")
		)
		(pad "3" smd rect
			(at 0 2.54)
			(size 1.651 0.8382)
			(layers "F.Cu" "F.Mask" "F.Paste")
			(net "GND")
		)
		(pad "4" smd rect
			(at 2.667 2.54)
			(size 1.651 0.8382)
			(layers "F.Cu" "F.Mask" "F.Paste")
			(net "CLK_156M_OSC_BRD_CPU0_DP")
		)
		(pad "5" smd rect
			(at 2.667 1.27)
			(size 1.651 0.8382)
			(layers "F.Cu" "F.Mask" "F.Paste")
			(net "CLK_156M_OSC_BRD_CPU0_DN")
		)
		(pad "6" smd rect
			(at 2.667 0)
			(size 1.651 0.8382)
			(layers "F.Cu" "F.Mask" "F.Paste")
			(net "P3V3")
		)
	)
	(footprint ""
		(layer "F.Cu")
		(at 211.831936 11.952478 -90)
		(property "Reference" "T1P3"
			(at 0 0 270)
			(layer "F.SilkS")
			(hide yes)
			(effects
				(font
					(size 1.27 1.27)
				)
			)
		)
		(property "Value" "*"
			(at -3.302 1.12395 270)
			(unlocked yes)
			(layer "F.Fab")
			(hide yes)
			(effects
				(font
					(size 0.889 0.889)
					(thickness 0.1524)
				)
			)
		)
		(property "Device Type" "TPAD-DIFF-4P-GP_DISCRET-GB3-TPA"
			(at -3.302 -0.40005 270)
			(unlocked yes)
			(layer "F.Fab")
			(hide yes)
			(effects
				(font
					(size 0.889 0.889)
					(thickness 0.1524)
				)
			)
		)
		(duplicate_pad_numbers_are_jumpers no)
		(fp_line
			(start -2.286 2.286)
			(end 2.286 2.286)
			(stroke
				(width 0.1524)
				(type default)
			)
			(layer "F.SilkS")
		)
		(fp_line
			(start 2.286 2.286)
			(end 2.286 -2.286)
			(stroke
				(width 0.1524)
				(type default)
			)
			(layer "F.SilkS")
		)
		(fp_line
			(start -2.286 -2.286)
			(end -2.286 2.286)
			(stroke
				(width 0.1524)
				(type default)
			)
			(layer "F.SilkS")
		)
		(fp_line
			(start 2.286 -2.286)
			(end -2.286 -2.286)
			(stroke
				(width 0.1524)
				(type default)
			)
			(layer "F.SilkS")
		)
		(fp_line
			(start -2.413 -2.413)
			(end -2.413 -1.143)
			(stroke
				(width 0.4064)
				(type default)
			)
			(layer "F.SilkS")
		)
		(fp_line
			(start -1.143 -2.413)
			(end -2.413 -2.413)
			(stroke
				(width 0.4064)
				(type default)
			)
			(layer "F.SilkS")
		)
		(fp_rect
			(start -2.54 2.54)
			(end 2.54 -2.54)
			(stroke
				(width 0)
				(type default)
			)
			(fill no)
			(layer "F.CrtYd")
		)
		(fp_rect
			(start -2.54 2.54)
			(end 2.54 -2.54)
			(stroke
				(width 0)
				(type default)
			)
			(fill no)
			(layer "F.Fab")
		)
		(pad "1" thru_hole circle
			(at -1.27 -1.27 270)
			(size 1.524 1.524)
			(drill 0.9144)
			(layers "*.Cu" "*.Mask")
			(remove_unused_layers no)
			(net "L5_85OHM_6INCH_DP")
			(clearance -0.0508)
			(thermal_gap 0.127)
			(padstack
				(mode front_inner_back)
				(layer "Inner"
					(shape circle)
					(size 1.1684 1.1684)
					(clearance 0.127)
				)
				(layer "B.Cu"
					(shape circle)
					(size 1.524 1.524)
					(clearance -0.0508)
				)
			)
		)
		(pad "2" thru_hole circle
			(at 1.27 -1.27 270)
			(size 1.524 1.524)
			(drill 0.9144)
			(layers "*.Cu" "*.Mask")
			(remove_unused_layers no)
			(net "L5_85OHM_6INCH_DN")
			(clearance -0.0508)
			(thermal_gap 0.127)
			(padstack
				(mode front_inner_back)
				(layer "Inner"
					(shape circle)
					(size 1.1684 1.1684)
					(clearance 0.127)
				)
				(layer "B.Cu"
					(shape circle)
					(size 1.524 1.524)
					(clearance -0.0508)
				)
			)
		)
		(pad "GND1" thru_hole rect
			(at -1.27 1.27 270)
			(size 1.524 1.524)
			(drill 0.9144)
			(layers "*.Cu" "*.Mask")
			(remove_unused_layers no)
			(net "GND")
			(clearance -0.0508)
			(thermal_gap 0.127)
			(padstack
				(mode front_inner_back)
				(layer "Inner"
					(shape circle)
					(size 1.1684 1.1684)
					(clearance 0.127)
				)
				(layer "B.Cu"
					(shape rect)
					(size 1.524 1.524)
					(clearance -0.0508)
				)
			)
		)
		(pad "GND2" thru_hole rect
			(at 1.27 1.27 270)
			(size 1.524 1.524)
			(drill 0.9144)
			(layers "*.Cu" "*.Mask")
			(remove_unused_layers no)
			(net "GND")
			(clearance -0.0508)
			(thermal_gap 0.127)
			(padstack
				(mode front_inner_back)
				(layer "Inner"
					(shape circle)
					(size 1.1684 1.1684)
					(clearance 0.127)
				)
				(layer "B.Cu"
					(shape rect)
					(size 1.524 1.524)
					(clearance -0.0508)
				)
			)
		)
	)
)
